# S9S_MB_2U (Grand Teton) — schematic netlist excerpt (pin names and nets, part order shuffled) for the footprints in the layout excerpt that follows; sources: Cadence DE-HDL packaged netlist, KiCad conversion of 03242023_DA0F0TMBIJ0_F0T_Motherboard_J_brd_V01_OCP.brd

J5  SCONN288_ADR50017P130CC  SCONN288_ADR50017-P130CC IO  pkg DDR288S_1-1VXB  page 86
  VIN_BULK0  = P12V_S3_AUX_CPU0_NVDIMM
  RFU0  = TP_CHC_CPU0_DIMM1_FRU_0
  VIN_MGMT  = P3V3_AUX
  HSCL  = I3C_SPD_DDRABCD_CPU0_LVC1_SCL_4
  HSDA  = I3C_SPD_DDRABCD_CPU0_LVC1_SDA
  VSS0  = GND
  DQ0_A  = M_C_CPU0_SA_DQ<0>
  VSS1  = GND
  DQ1_A  = M_C_CPU0_SA_DQ<1>
  VSS2  = GND
  DQS0_A_T  = M_C_CPU0_SA_DQS_DP<0>
  DQS0_A_C  = M_C_CPU0_SA_DQS_DN<0>
  VSS3  = GND
  DQ4_A  = M_C_CPU0_SA_DQ<4>
  VSS4  = GND
  DQ5_A  = M_C_CPU0_SA_DQ<5>
  VSS5  = GND
  DQ8_A  = M_C_CPU0_SA_DQ<8>
  VSS6  = GND
  DQ9_A  = M_C_CPU0_SA_DQ<9>
  VSS7  = GND
  DQS1_A_T  = M_C_CPU0_SA_DQS_DP<1>
  DQS1_A_C  = M_C_CPU0_SA_DQS_DN<1>
  VSS8  = GND
  DQ12_A  = M_C_CPU0_SA_DQ<12>
  VSS9  = GND
  DQ13_A  = M_C_CPU0_SA_DQ<13>
  VSS10  = GND
  DQ16_A  = M_C_CPU0_SA_DQ<16>
  VSS11  = GND
  DQ17_A  = M_C_CPU0_SA_DQ<17>
  VSS12  = GND
  DQS2_A_T  = M_C_CPU0_SA_DQS_DP<2>
  DQS2_A_C  = M_C_CPU0_SA_DQS_DN<2>
  VSS13  = GND
  DQ20_A  = M_C_CPU0_SA_DQ<20>
  VSS14  = GND
  DQ21_A  = M_C_CPU0_SA_DQ<21>
  VSS15  = GND
  DQ24_A  = M_C_CPU0_SA_DQ<24>
  VSS16  = GND
  DQ25_A  = M_C_CPU0_SA_DQ<25>
  VSS17  = GND
  DQS3_A_T  = M_C_CPU0_SA_DQS_DP<3>
  DQS3_A_C  = M_C_CPU0_SA_DQS_DN<3>
  VSS18  = GND
  DQ28_A  = M_C_CPU0_SA_DQ<28>
  VSS19  = GND
  DQ29_A  = M_C_CPU0_SA_DQ<29>
  VSS20  = GND
  CB0_A  = M_C_CPU0_SA_CB<0>
  VSS21  = GND
  CB1_A  = M_C_CPU0_SA_CB<1>
  VSS22  = GND
  DQS4_A_T  = M_C_CPU0_SA_DQS_DP<4>
  DQS4_A_C  = M_C_CPU0_SA_DQS_DN<4>
  VSS23  = GND
  CB4_A  = M_C_CPU0_SA_CB<4>
  VSS24  = GND
  CB5_A  = M_C_CPU0_SA_CB<5>
  VSS25  = GND
  ALERT_N  = M_C_CPU0_ALERT_N
  VSS26  = GND
  CS0_A_N  = M_C_CPU0_SA_CS_N<0>
  VSS27  = GND
  CA0_A  = M_C_CPU0_SA_CA<0>
  VSS28  = GND
  CA2_A  = M_C_CPU0_SA_CA<2>
  VSS29  = GND
  CA4_A  = M_C_CPU0_SA_CA<4>
  VSS30  = GND
  CA6_A  = M_C_CPU0_SA_CA<6>
  VSS31  = GND
  PAR_A  = M_C_CPU0_SA_PAR
  VSS32  = GND
  CA0_B  = M_C_CPU0_SB_CA<0>
  VSS33  = GND
  CA2_B  = M_C_CPU0_SB_CA<2>
  VSS34  = GND
  CA4_B  = M_C_CPU0_SB_CA<4>
  VSS35  = GND
  CA6_B  = M_C_CPU0_SB_CA<6>
  VSS36  = GND
  CS0_B_N  = M_C_CPU0_SB_CS_N<0>
  VSS37  = GND
  \lbd||rsp_a_n\  = M_C_CPU0_SA_RSP<0>
  \lbs||rsp_b_n\  = M_C_CPU0_SB_RSP<0>
  VSS38  = GND
  CB4_B  = M_C_CPU0_SB_CB<4>
  VSS39  = GND
  CB5_B  = M_C_CPU0_SB_CB<5>
  VSS40  = GND
  \dqs9_b_t||tdqs9_b_t||dbi4_b_n\  = M_C_CPU0_SB_DQS_DP<9>
  \dqs9_b_c||tdqs9_b_c\  = M_C_CPU0_SB_DQS_DN<9>
  VSS41  = GND
  CB0_B  = M_C_CPU0_SB_CB<0>
  VSS42  = GND
  CB1_B  = M_C_CPU0_SB_CB<1>
  VSS43  = GND
  DQ0_B  = M_C_CPU0_SB_DQ<0>
  VSS44  = GND
  DQ1_B  = M_C_CPU0_SB_DQ<1>
  VSS45  = GND
  DQS0_B_T  = M_C_CPU0_SB_DQS_DP<0>
  DQS0_B_C  = M_C_CPU0_SB_DQS_DN<0>
  VSS46  = GND
  DQ4_B  = M_C_CPU0_SB_DQ<4>
  VSS47  = GND
  DQ5_B  = M_C_CPU0_SB_DQ<5>
  VSS48  = GND
  DQ8_B  = M_C_CPU0_SB_DQ<8>
  VSS49  = GND
  DQ9_B  = M_C_CPU0_SB_DQ<9>
  VSS50  = GND
  DQS1_B_T  = M_C_CPU0_SB_DQS_DP<1>
  DQS1_B_C  = M_C_CPU0_SB_DQS_DN<1>
  VSS51  = GND
  DQ12_B  = M_C_CPU0_SB_DQ<12>
  VSS52  = GND
  DQ13_B  = M_C_CPU0_SB_DQ<13>
  VSS53  = GND
  DQ16_B  = M_C_CPU0_SB_DQ<16>
  VSS54  = GND
  DQ17_B  = M_C_CPU0_SB_DQ<17>
  VSS55  = GND
  DQS2_B_T  = M_C_CPU0_SB_DQS_DP<2>
  DQS2_B_C  = M_C_CPU0_SB_DQS_DN<2>
  VSS56  = GND
  DQ20_B  = M_C_CPU0_SB_DQ<20>
  VSS57  = GND
  DQ21_B  = M_C_CPU0_SB_DQ<21>
  VSS58  = GND
  DQ24_B  = M_C_CPU0_SB_DQ<24>
  VSS59  = GND
  DQ25_B  = M_C_CPU0_SB_DQ<25>
  VSS60  = GND
  DQS3_B_T  = M_C_CPU0_SB_DQS_DP<3>
  DQS3_B_C  = M_C_CPU0_SB_DQS_DN<3>
  VSS61  = GND
  DQ28_B  = M_C_CPU0_SB_DQ<28>
  VSS62  = GND
  DQ29_B  = M_C_CPU0_SB_DQ<29>
  VSS63  = GND
  RFU1  = TP_CHC_CPU0_DIMM1_FRU_1
  VIN_BULK1  = P12V_S3_AUX_CPU0_NVDIMM
  VIN_BULK2  = P12V_S3_AUX_CPU0_NVDIMM
  \pwr_good||fail_n\  = PWRGD_CHC_CPU0_DIMM1
  HSA  = PD_CHC_CPU0_DIMM1_SAA
  RFU2  = TP_CHC_CPU0_DIMM1_FRU_2
  RFU3  = TP_CHC_CPU0_DIMM1_FRU_3
  VSS64  = GND
  DQ2_A  = M_C_CPU0_SA_DQ<2>
  VSS65  = GND
  DQ3_A  = M_C_CPU0_SA_DQ<3>
  VSS66  = GND
  \dqs5_a_c||tdqs5_a_c||dqs5_a_t||tdqs5_a_t\  = M_C_CPU0_SA_DQS_DN<5>
  \dqs5_a_t||tdqs5_a_t\  = M_C_CPU0_SA_DQS_DP<5>
  VSS67  = GND
  DQ6_A  = M_C_CPU0_SA_DQ<6>
  VSS68  = GND
  DQ7_A  = M_C_CPU0_SA_DQ<7>
  VSS69  = GND
  DQ10_A  = M_C_CPU0_SA_DQ<10>
  VSS70  = GND
  DQ11_A  = M_C_CPU0_SA_DQ<11>
  VSS71  = GND
  \dqs6_a_c||tdqs6_a_c||dqs6_a_t||tdqs6_a_t\  = M_C_CPU0_SA_DQS_DN<6>
  \dqs6_a_t||tdqs6_a_t\  = M_C_CPU0_SA_DQS_DP<6>
  VSS72  = GND
  DQ14_A  = M_C_CPU0_SA_DQ<14>
  VSS73  = GND
  DQ15_A  = M_C_CPU0_SA_DQ<15>
  VSS74  = GND
  DQ18_A  = M_C_CPU0_SA_DQ<18>
  VSS75  = GND
  DQ19_A  = M_C_CPU0_SA_DQ<19>
  VSS76  = GND
  \dqs7_a_c||tdqs7_a_c\  = M_C_CPU0_SA_DQS_DN<7>
  \dqs7_a_t||tdqs7_a_t\  = M_C_CPU0_SA_DQS_DP<7>
  VSS77  = GND
  DQ22_A  = M_C_CPU0_SA_DQ<22>
  VSS78  = GND
  DQ23_A  = M_C_CPU0_SA_DQ<23>
  VSS79  = GND
  DQ26_A  = M_C_CPU0_SA_DQ<26>
  VSS80  = GND
  DQ27_A  = M_C_CPU0_SA_DQ<27>
  VSS81  = GND
  \dqs8_a_c||tdqs8_a_c\  = M_C_CPU0_SA_DQS_DN<8>
  \dqs8_a_t||tdqs8_a_t\  = M_C_CPU0_SA_DQS_DP<8>
  VSS82  = GND
  DQ30_A  = M_C_CPU0_SA_DQ<30>
  VSS83  = GND
  DQ31_A  = M_C_CPU0_SA_DQ<31>
  VSS84  = GND
  CB2_A  = M_C_CPU0_SA_CB<2>
  VSS85  = GND
  CB3_A  = M_C_CPU0_SA_CB<3>
  VSS86  = GND
  \dqs9_a_c||tdqs9_a_c\  = M_C_CPU0_SA_DQS_DN<9>
  \dqs9_a_t||tdqs9_a_t\  = M_C_CPU0_SA_DQS_DP<9>
  VSS87  = GND
  CB6_A  = M_C_CPU0_SA_CB<6>
  VSS88  = GND
  CB7_A  = M_C_CPU0_SA_CB<7>
  VSS89  = GND
  RESET_N  = RST_M_CD_CPU0_FPGA_N
  VSS90  = GND
  CS1_A_N  = M_C_CPU0_SA_CS_N<1>
  VSS91  = GND
  CA1_A  = M_C_CPU0_SA_CA<1>
  VSS92  = GND
  CA3_A  = M_C_CPU0_SA_CA<3>
  VSS93  = GND
  CA5_A  = M_C_CPU0_SA_CA<5>
  VSS94  = GND
  CK_T  = M_C_CPU0_CLK_DP<0>
  CK_C  = M_C_CPU0_CLK_DN<0>
  VSS95  = GND
  RFU4  = TP_CHC_CPU0_DIMM1_FRU_4
  CA1_B  = M_C_CPU0_SB_CA<1>
  VSS96  = GND
  CA3_B  = M_C_CPU0_SB_CA<3>
  VSS97  = GND
  CA5_B  = M_C_CPU0_SB_CA<5>
  VSS98  = GND
  PAR_B  = M_C_CPU0_SB_PAR
  VSS99  = GND
  CS1_B_N  = M_C_CPU0_SB_CS_N<1>
  VSS100  = GND
  RFU5  = TP_CHC_CPU0_DIMM1_FRU_5
  RFU6  = TP_CHC_CPU0_DIMM1_FRU_6
  VSS101  = GND
  CB6_B  = M_C_CPU0_SB_CB<6>
  VSS102  = GND
  CB7_B  = M_C_CPU0_SB_CB<7>
  VSS103  = GND
  DQS4_B_C  = M_C_CPU0_SB_DQS_DN<4>
  DQS4_B_T  = M_C_CPU0_SB_DQS_DP<4>
  VSS104  = GND
  CB2_B  = M_C_CPU0_SB_CB<2>
  VSS105  = GND
  CB3_B  = M_C_CPU0_SB_CB<3>
  VSS106  = GND
  DQ2_B  = M_C_CPU0_SB_DQ<2>
  VSS107  = GND
  DQ3_B  = M_C_CPU0_SB_DQ<3>
  VSS108  = GND
  \dqs5_b_c||tdqs5_b_c\  = M_C_CPU0_SB_DQS_DN<5>
  \dqs5_b_t||tdqs5_b_t\  = M_C_CPU0_SB_DQS_DP<5>
  VSS109  = GND
  DQ6_B  = M_C_CPU0_SB_DQ<6>
  VSS110  = GND
  DQ7_B  = M_C_CPU0_SB_DQ<7>
  VSS111  = GND
  DQ10_B  = M_C_CPU0_SB_DQ<10>
  VSS112  = GND
  DQ11_B  = M_C_CPU0_SB_DQ<11>
  VSS113  = GND
  \dqs6_b_c||tdqs6_b_c\  = M_C_CPU0_SB_DQS_DN<6>
  \dqs6_b_t||tdqs6_b_t\  = M_C_CPU0_SB_DQS_DP<6>
  VSS114  = GND
  DQ14_B  = M_C_CPU0_SB_DQ<14>
  VSS115  = GND
  DQ15_B  = M_C_CPU0_SB_DQ<15>
  VSS116  = GND
  DQ18_B  = M_C_CPU0_SB_DQ<18>
  VSS117  = GND
  DQ19_B  = M_C_CPU0_SB_DQ<19>
  VSS118  = GND
  \dqs7_b_c||tdqs7_b_c\  = M_C_CPU0_SB_DQS_DN<7>
  \dqs7_b_t||tdqs7_b_t\  = M_C_CPU0_SB_DQS_DP<7>
  VSS119  = GND
  DQ22_B  = M_C_CPU0_SB_DQ<22>
  VSS120  = GND
  DQ23_B  = M_C_CPU0_SB_DQ<23>
  VSS121  = GND
  DQ26_B  = M_C_CPU0_SB_DQ<26>
  VSS122  = GND
  DQ27_B  = M_C_CPU0_SB_DQ<27>
  VSS123  = GND
  \dqs8_b_c||tdqs8_b_c\  = M_C_CPU0_SB_DQS_DN<8>
  \dqs8_b_t||tdqs8_b_t\  = M_C_CPU0_SB_DQS_DP<8>
  VSS124  = GND
  DQ30_B  = M_C_CPU0_SB_DQ<30>
  VSS125  = GND
  DQ31_B  = M_C_CPU0_SB_DQ<31>
  VSS126  = GND
  G1  = GND
  G2  = GND
  G3  = GND

(kicad_pcb
	(version 20260206)
	(generator "pcbnew")
	(generator_version "10.0")
	(general
		(thickness 1.6)
		(legacy_teardrops no)
	)
	(paper "A4")
	(title_block
		(title "03242023_DA0F0TMBIJ0_F0T_Motherboard_J_brd_V01_OCP.brd")
		(comment 1 "Grand Teton / footprint 885 of 6105 (J5), pads 1-45 of 291")
	)
	(layers
		(0 "F.Cu" signal "TOP")
		(4 "In1.Cu" signal "GND")
		(6 "In2.Cu" signal "IN1")
		(8 "In3.Cu" signal "GND1")
		(10 "In4.Cu" signal "IN2")
		(12 "In5.Cu" signal "GND2")
		(14 "In6.Cu" signal "IN3")
		(16 "In7.Cu" signal "GND3")
		(18 "In8.Cu" signal "VCC")
		(20 "In9.Cu" signal "VCC1")
		(22 "In10.Cu" signal "GND4")
		(24 "In11.Cu" signal "IN4")
		(26 "In12.Cu" signal "GND5")
		(28 "In13.Cu" signal "IN5")
		(30 "In14.Cu" signal "GND6")
		(32 "In15.Cu" signal "IN6")
		(34 "In16.Cu" signal "GND7")
		(2 "B.Cu" signal "BOTTOM")
		(9 "F.Adhes" user "F.Adhesive")
		(11 "B.Adhes" user "B.Adhesive")
		(13 "F.Paste" user "Package Geometry/Pastemask Top")
		(15 "B.Paste" user "Package Geometry/Pastemask Bottom")
		(5 "F.SilkS" user "Ref Des/Silkscreen Top")
		(7 "B.SilkS" user "Ref Des/Silkscreen Bottom")
		(1 "F.Mask" user "Board Geometry/Soldermask Top")
		(3 "B.Mask" user "Board Geometry/Soldermask Bottom")
		(17 "Dwgs.User" user "User.Drawings")
		(19 "Cmts.User" user "User.Comments")
		(21 "Eco1.User" user "User.Eco1")
		(23 "Eco2.User" user "User.Eco2")
		(25 "Edge.Cuts" user "Board Geometry/Outline")
		(27 "Margin" user)
		(31 "F.CrtYd" user "Package Geometry/Place Bound Top")
		(29 "B.CrtYd" user "Package Geometry/Place Bound Bottom")
		(35 "F.Fab" user "Ref Des/Assembly Top")
		(33 "B.Fab" user "Ref Des/Assembly Bottom")
	)
	(footprint ""
		(layer "F.Cu")
		(at 273.218148 -258.091686)
		(property "Reference" "J5"
			(at -3.683 -81.702148 0)
			(unlocked yes)
			(layer "F.SilkS")
			(effects
				(font
					(size 0.7874 0.5842)
					(thickness 0.1524)
				)
				(justify left)
			)
		)
		(property "Value" ""
			(at 0 0 0)
			(layer "F.Fab")
			(effects
				(font
					(size 1.27 1.27)
				)
			)
		)
		(duplicate_pad_numbers_are_jumpers no)
		(pad "1" smd rect
			(at -2.050034 -63.324994 270)
			(size 0.519938 1.4986)
			(layers "F.Cu" "F.Mask" "F.Paste")
			(net "P12V_S3_AUX_CPU0_NVDIMM")
		)
		(pad "2" smd rect
			(at -2.050034 -62.47511 270)
			(size 0.519938 1.4986)
			(layers "F.Cu" "F.Mask" "F.Paste")
			(net "TP_CHC_CPU0_DIMM1_FRU_0")
		)
		(pad "3" smd rect
			(at -2.050034 -61.624972 270)
			(size 0.519938 1.4986)
			(layers "F.Cu" "F.Mask" "F.Paste")
			(net "P3V3_AUX")
		)
		(pad "4" smd rect
			(at -2.050034 -60.775088 270)
			(size 0.519938 1.4986)
			(layers "F.Cu" "F.Mask" "F.Paste")
			(net "I3C_SPD_DDRABCD_CPU0_LVC1_SCL_4")
		)
		(pad "5" smd rect
			(at -2.050034 -59.92495 270)
			(size 0.519938 1.4986)
			(layers "F.Cu" "F.Mask" "F.Paste")
			(net "I3C_SPD_DDRABCD_CPU0_LVC1_SDA")
		)
		(pad "6" smd rect
			(at -2.050034 -59.075066 270)
			(size 0.519938 1.4986)
			(layers "F.Cu" "F.Mask" "F.Paste")
			(net "GND")
		)
		(pad "7" smd rect
			(at -2.050034 -58.224928 270)
			(size 0.519938 1.4986)
			(layers "F.Cu" "F.Mask" "F.Paste")
			(net "M_C_CPU0_SA_DQ<0>")
		)
		(pad "8" smd rect
			(at -2.050034 -57.375044 270)
			(size 0.519938 1.4986)
			(layers "F.Cu" "F.Mask" "F.Paste")
			(net "GND")
		)
		(pad "9" smd rect
			(at -2.050034 -56.524906 270)
			(size 0.519938 1.4986)
			(layers "F.Cu" "F.Mask" "F.Paste")
			(net "M_C_CPU0_SA_DQ<1>")
		)
		(pad "10" smd rect
			(at -2.050034 -55.675022 270)
			(size 0.519938 1.4986)
			(layers "F.Cu" "F.Mask" "F.Paste")
			(net "GND")
		)
		(pad "11" smd rect
			(at -2.050034 -54.824884 270)
			(size 0.519938 1.4986)
			(layers "F.Cu" "F.Mask" "F.Paste")
			(net "M_C_CPU0_SA_DQS_DP<0>")
		)
		(pad "12" smd rect
			(at -2.050034 -53.975 270)
			(size 0.519938 1.4986)
			(layers "F.Cu" "F.Mask" "F.Paste")
			(net "M_C_CPU0_SA_DQS_DN<0>")
		)
		(pad "13" smd rect
			(at -2.050034 -53.125116 270)
			(size 0.519938 1.4986)
			(layers "F.Cu" "F.Mask" "F.Paste")
			(net "GND")
		)
		(pad "14" smd rect
			(at -2.050034 -52.274978 270)
			(size 0.519938 1.4986)
			(layers "F.Cu" "F.Mask" "F.Paste")
			(net "M_C_CPU0_SA_DQ<4>")
		)
		(pad "15" smd rect
			(at -2.050034 -51.425094 270)
			(size 0.519938 1.4986)
			(layers "F.Cu" "F.Mask" "F.Paste")
			(net "GND")
		)
		(pad "16" smd rect
			(at -2.050034 -50.574956 270)
			(size 0.519938 1.4986)
			(layers "F.Cu" "F.Mask" "F.Paste")
			(net "M_C_CPU0_SA_DQ<5>")
		)
		(pad "17" smd rect
			(at -2.050034 -49.725072 270)
			(size 0.519938 1.4986)
			(layers "F.Cu" "F.Mask" "F.Paste")
			(net "GND")
		)
		(pad "18" smd rect
			(at -2.050034 -48.874934 270)
			(size 0.519938 1.4986)
			(layers "F.Cu" "F.Mask" "F.Paste")
			(net "M_C_CPU0_SA_DQ<8>")
		)
		(pad "19" smd rect
			(at -2.050034 -48.02505 270)
			(size 0.519938 1.4986)
			(layers "F.Cu" "F.Mask" "F.Paste")
			(net "GND")
		)
		(pad "20" smd rect
			(at -2.050034 -47.174912 270)
			(size 0.519938 1.4986)
			(layers "F.Cu" "F.Mask" "F.Paste")
			(net "M_C_CPU0_SA_DQ<9>")
		)
		(pad "21" smd rect
			(at -2.050034 -46.325028 270)
			(size 0.519938 1.4986)
			(layers "F.Cu" "F.Mask" "F.Paste")
			(net "GND")
		)
		(pad "22" smd rect
			(at -2.050034 -45.47489 270)
			(size 0.519938 1.4986)
			(layers "F.Cu" "F.Mask" "F.Paste")
			(net "M_C_CPU0_SA_DQS_DP<1>")
		)
		(pad "23" smd rect
			(at -2.050034 -44.625006 270)
			(size 0.519938 1.4986)
			(layers "F.Cu" "F.Mask" "F.Paste")
			(net "M_C_CPU0_SA_DQS_DN<1>")
		)
		(pad "24" smd rect
			(at -2.050034 -43.775122 270)
			(size 0.519938 1.4986)
			(layers "F.Cu" "F.Mask" "F.Paste")
			(net "GND")
		)
		(pad "25" smd rect
			(at -2.050034 -42.924984 270)
			(size 0.519938 1.4986)
			(layers "F.Cu" "F.Mask" "F.Paste")
			(net "M_C_CPU0_SA_DQ<12>")
		)
		(pad "26" smd rect
			(at -2.050034 -42.0751 270)
			(size 0.519938 1.4986)
			(layers "F.Cu" "F.Mask" "F.Paste")
			(net "GND")
		)
		(pad "27" smd rect
			(at -2.050034 -41.224962 270)
			(size 0.519938 1.4986)
			(layers "F.Cu" "F.Mask" "F.Paste")
			(net "M_C_CPU0_SA_DQ<13>")
		)
		(pad "28" smd rect
			(at -2.050034 -40.375078 270)
			(size 0.519938 1.4986)
			(layers "F.Cu" "F.Mask" "F.Paste")
			(net "GND")
		)
		(pad "29" smd rect
			(at -2.050034 -39.52494 270)
			(size 0.519938 1.4986)
			(layers "F.Cu" "F.Mask" "F.Paste")
			(net "M_C_CPU0_SA_DQ<16>")
		)
		(pad "30" smd rect
			(at -2.050034 -38.675056 270)
			(size 0.519938 1.4986)
			(layers "F.Cu" "F.Mask" "F.Paste")
			(net "GND")
		)
		(pad "31" smd rect
			(at -2.050034 -37.824918 270)
			(size 0.519938 1.4986)
			(layers "F.Cu" "F.Mask" "F.Paste")
			(net "M_C_CPU0_SA_DQ<17>")
		)
		(pad "32" smd rect
			(at -2.050034 -36.975034 270)
			(size 0.519938 1.4986)
			(layers "F.Cu" "F.Mask" "F.Paste")
			(net "GND")
		)
		(pad "33" smd rect
			(at -2.050034 -36.124896 270)
			(size 0.519938 1.4986)
			(layers "F.Cu" "F.Mask" "F.Paste")
			(net "M_C_CPU0_SA_DQS_DP<2>")
		)
		(pad "34" smd rect
			(at -2.050034 -35.275012 270)
			(size 0.519938 1.4986)
			(layers "F.Cu" "F.Mask" "F.Paste")
			(net "M_C_CPU0_SA_DQS_DN<2>")
		)
		(pad "35" smd rect
			(at -2.050034 -34.425128 270)
			(size 0.519938 1.4986)
			(layers "F.Cu" "F.Mask" "F.Paste")
			(net "GND")
		)
		(pad "36" smd rect
			(at -2.050034 -33.57499 270)
			(size 0.519938 1.4986)
			(layers "F.Cu" "F.Mask" "F.Paste")
			(net "M_C_CPU0_SA_DQ<20>")
		)
		(pad "37" smd rect
			(at -2.050034 -32.725106 270)
			(size 0.519938 1.4986)
			(layers "F.Cu" "F.Mask" "F.Paste")
			(net "GND")
		)
		(pad "38" smd rect
			(at -2.050034 -31.874968 270)
			(size 0.519938 1.4986)
			(layers "F.Cu" "F.Mask" "F.Paste")
			(net "M_C_CPU0_SA_DQ<21>")
		)
		(pad "39" smd rect
			(at -2.050034 -31.025084 270)
			(size 0.519938 1.4986)
			(layers "F.Cu" "F.Mask" "F.Paste")
			(net "GND")
		)
		(pad "40" smd rect
			(at -2.050034 -30.174946 270)
			(size 0.519938 1.4986)
			(layers "F.Cu" "F.Mask" "F.Paste")
			(net "M_C_CPU0_SA_DQ<24>")
		)
		(pad "41" smd rect
			(at -2.050034 -29.325062 270)
			(size 0.519938 1.4986)
			(layers "F.Cu" "F.Mask" "F.Paste")
			(net "GND")
		)
		(pad "42" smd rect
			(at -2.050034 -28.474924 270)
			(size 0.519938 1.4986)
			(layers "F.Cu" "F.Mask" "F.Paste")
			(net "M_C_CPU0_SA_DQ<25>")
		)
		(pad "43" smd rect
			(at -2.050034 -27.62504 270)
			(size 0.519938 1.4986)
			(layers "F.Cu" "F.Mask" "F.Paste")
			(net "GND")
		)
		(pad "44" smd rect
			(at -2.050034 -26.774902 270)
			(size 0.519938 1.4986)
			(layers "F.Cu" "F.Mask" "F.Paste")
			(net "M_C_CPU0_SA_DQS_DP<3>")
		)
		(pad "45" smd rect
			(at -2.050034 -25.925018 270)
			(size 0.519938 1.4986)
			(layers "F.Cu" "F.Mask" "F.Paste")
			(net "M_C_CPU0_SA_DQS_DN<3>")
		)
	)
)
